;EXTENTS: -50.000 -50.000 470.000 580.000 
;LEADER: 12 
;HEADER: 
;CODE  : ASCII 
;FILE  : G:/<user>/F/F0T/F0T_Eexpender_BD/F/0110/07_Export_Files/upload_report/01102023_DA0F0TEBIF0_F0T_Expander_BD_F_artwork/9127_F0T_Expander_BD_F_v02_0110_1240_1-18.rou for board G:/<user>/F/F0T/F0T_Eexpender_BD/F/0110/07_Export_Files/upload_report/01102023_DA0F0TEBIF0_F0T_Expander_BD_F_artwork/#Taaaago27144.tmp, layers TOP to BOTTOM
%
G90
F1
M16
T02
M16
G00X1726739Y0060709
G40
M15
G01X1732039Y0060709
M16
G00X1726739Y0150197
G40
M15
G01X1732039Y0150197
M16
G00X1624377Y0060709
G40
M15
G01X1629677Y0060709
M16
G00X1624377Y0150197
G40
M15
G01X1629677Y0150197
M16
G00X1522015Y0060709
G40
M15
G01X1527315Y0060709
M16
G00X1522015Y0150197
G40
M15
G01X1527315Y0150197
M16
G00X1419653Y0060709
G40
M15
G01X1424953Y0060709
M16
G00X1419653Y0150197
G40
M15
G01X1424953Y0150197
M16
G00X1269652Y0060709
G40
M15
G01X1274952Y0060709
M16
G00X1269652Y0150197
G40
M15
G01X1274952Y0150197
M16
G00X1167290Y0060709
G40
M15
G01X1172590Y0060709
M16
G00X1167290Y0150197
G40
M15
G01X1172590Y0150197
M16
G00X1064928Y0060709
G40
M15
G01X1070228Y0060709
M16
G00X1064928Y0150197
G40
M15
G01X1070228Y0150197
M16
G00X0962566Y0060709
G40
M15
G01X0967866Y0060709
M16
G00X0962566Y0150197
G40
M15
G01X0967866Y0150197
M16
G00X0812566Y0060709
G40
M15
G01X0817866Y0060709
M16
G00X0812566Y0150197
G40
M15
G01X0817866Y0150197
M16
G00X0710204Y0060709
G40
M15
G01X0715504Y0060709
M16
G00X0710204Y0150197
G40
M15
G01X0715504Y0150197
M16
G00X0607842Y0060709
G40
M15
G01X0613142Y0060709
M16
G00X0607842Y0150197
G40
M15
G01X0613142Y0150197
M16
G00X0505480Y0060709
G40
M15
G01X0510780Y0060709
M16
G00X0505480Y0150197
G40
M15
G01X0510780Y0150197
M16
G00X0355479Y0060709
G40
M15
G01X0360779Y0060709
M16
G00X0355479Y0150197
G40
M15
G01X0360779Y0150197
M16
G00X0253117Y0060709
G40
M15
G01X0258417Y0060709
M16
G00X0253117Y0150197
G40
M15
G01X0258417Y0150197
M16
G00X0150755Y0060709
G40
M15
G01X0156055Y0060709
M16
G00X0150755Y0150197
G40
M15
G01X0156055Y0150197
M16
G00X0048393Y0060709
G40
M15
G01X0053693Y0060709
M16
G00X0048393Y0150197
G40
M15
G01X0053693Y0150197
M16
G00X0187675Y0636752
G40
M15
G01X0192975Y0636752
M16
G00X0187675Y0583957
G40
M15
G01X0192975Y0583957
M16
G00X0187675Y0503760
G40
M15
G01X0192975Y0503760
M16
G00X0187675Y0455492
G40
M15
G01X0192975Y0455492
M16
G00X0187675Y0368760
G40
M15
G01X0192975Y0368760
M16
G00X0276710Y0368760
G40
M15
G01X0282010Y0368760
M16
G00X0276710Y0421555
G40
M15
G01X0282010Y0421555
M16
G00X0276710Y0501752
G40
M15
G01X0282010Y0501752
M16
G00X0276710Y0550020
G40
M15
G01X0282010Y0550020
M16
G00X0276710Y0636752
G40
M15
G01X0282010Y0636752
M16
G00X0644761Y0636752
G40
M15
G01X0650061Y0636752
M16
G00X0644761Y0583957
G40
M15
G01X0650061Y0583957
M16
G00X0644761Y0503760
G40
M15
G01X0650061Y0503760
M16
G00X0644761Y0455492
G40
M15
G01X0650061Y0455492
M16
G00X0644761Y0368760
G40
M15
G01X0650061Y0368760
M16
G00X0733796Y0368760
G40
M15
G01X0739096Y0368760
M16
G00X0733796Y0421555
G40
M15
G01X0739096Y0421555
M16
G00X0733796Y0501752
G40
M15
G01X0739096Y0501752
M16
G00X0733796Y0550020
G40
M15
G01X0739096Y0550020
M16
G00X0733796Y0636752
G40
M15
G01X0739096Y0636752
M16
G00X1101848Y0636752
G40
M15
G01X1107148Y0636752
M16
G00X1101848Y0583957
G40
M15
G01X1107148Y0583957
M16
G00X1101848Y0503760
G40
M15
G01X1107148Y0503760
M16
G00X1101848Y0455492
G40
M15
G01X1107148Y0455492
M16
G00X1101848Y0368760
G40
M15
G01X1107148Y0368760
M16
G00X1190883Y0368760
G40
M15
G01X1196183Y0368760
M16
G00X1190883Y0421555
G40
M15
G01X1196183Y0421555
M16
G00X1190883Y0501752
G40
M15
G01X1196183Y0501752
M16
G00X1190883Y0550020
G40
M15
G01X1196183Y0550020
M16
G00X1190883Y0636752
G40
M15
G01X1196183Y0636752
M16
G00X1558935Y0636752
G40
M15
G01X1564235Y0636752
M16
G00X1558935Y0583957
G40
M15
G01X1564235Y0583957
M16
G00X1558935Y0503760
G40
M15
G01X1564235Y0503760
M16
G00X1558935Y0455492
G40
M15
G01X1564235Y0455492
M16
G00X1558935Y0368760
G40
M15
G01X1564235Y0368760
M16
G00X1647970Y0368760
G40
M15
G01X1653270Y0368760
M16
G00X1647970Y0421555
G40
M15
G01X1653270Y0421555
M16
G00X1647970Y0501752
G40
M15
G01X1653270Y0501752
M16
G00X1647970Y0550020
G40
M15
G01X1653270Y0550020
M16
G00X1647970Y0636752
G40
M15
G01X1653270Y0636752
M16
T01
M16
G00X1795452Y0811474
G40
M15
G01X1795452Y0814274
M16
G00X1795452Y0833521
G40
M15
G01X1795452Y0836321
M16
G00X1803916Y0821747
G40
M15
G01X1803916Y0826047
M16
G40
M30
